# BASEBOARD_FAB2 (Tioga Pass) — schematic netlist excerpt (pin names and nets, part order shuffled) for the footprints in the layout excerpt that follows; sources: Cadence DE-HDL packaged netlist, KiCad conversion of Wiwynn_Tioga_Pass_MB.brd

R7C4  RES  0.0 5% CHIP  pkg 0402  page 114 : A = CLK_100M_BMC_PE_R_DP ; B = CLK_100M_BMC_PE_DP
C8A14  CAP  22UF 6.3V 20% X6S  pkg 0805  page 237 : A = P1V8_PCH_STBY ; B = GND
R9E21  RES  4.75K 1% CHIP  pkg 0402  page 151 : A = P3V3_STBY ; B = FM_HEARTBEAT_LED

(kicad_pcb
	(version 20260206)
	(generator "pcbnew")
	(generator_version "10.0")
	(general
		(thickness 1.6)
		(legacy_teardrops no)
	)
	(paper "A4")
	(title_block
		(title "Wiwynn_Tioga_Pass_MB.brd")
		(comment 1 "Tioga Pass / footprints 1236-1238 of 4770")
	)
	(layers
		(0 "F.Cu" signal "TOP")
		(4 "In1.Cu" signal "L2GND")
		(6 "In2.Cu" signal "L3")
		(8 "In3.Cu" signal "L4GND")
		(10 "In4.Cu" signal "L5")
		(12 "In5.Cu" signal "L6GND")
		(14 "In6.Cu" signal "L7VCC")
		(16 "In7.Cu" signal "L8VCC")
		(18 "In8.Cu" signal "L9GND")
		(20 "In9.Cu" signal "L10")
		(22 "In10.Cu" signal "L11GND")
		(24 "In11.Cu" signal "L12")
		(26 "In12.Cu" signal "L13GND")
		(2 "B.Cu" signal "BOTTOM")
		(9 "F.Adhes" user "F.Adhesive")
		(11 "B.Adhes" user "B.Adhesive")
		(13 "F.Paste" user "Package Geometry/Pastemask Top")
		(15 "B.Paste" user "Package Geometry/Pastemask Bottom")
		(5 "F.SilkS" user "Ref Des/Silkscreen Top")
		(7 "B.SilkS" user "Ref Des/Silkscreen Bottom")
		(1 "F.Mask" user "Board Geometry/Soldermask Top")
		(3 "B.Mask" user "Board Geometry/Soldermask Bottom")
		(17 "Dwgs.User" user "User.Drawings")
		(19 "Cmts.User" user "User.Comments")
		(21 "Eco1.User" user "User.Eco1")
		(23 "Eco2.User" user "User.Eco2")
		(25 "Edge.Cuts" user "Board Geometry/Outline")
		(27 "Margin" user)
		(31 "F.CrtYd" user "Package Geometry/Place Bound Top")
		(29 "B.CrtYd" user "Package Geometry/Place Bound Bottom")
		(35 "F.Fab" user "Ref Des/Assembly Top")
		(33 "B.Fab" user "Ref Des/Assembly Bottom")
	)
	(footprint ""
		(layer "F.Cu")
		(at 455.422 -38.735)
		(property "Reference" "R9E21"
			(at 0 0 0)
			(layer "F.SilkS")
			(hide yes)
			(effects
				(font
					(size 1.27 1.27)
				)
			)
		)
		(property "Value" ""
			(at 0 0 0)
			(layer "F.Fab")
			(effects
				(font
					(size 1.27 1.27)
				)
			)
		)
		(duplicate_pad_numbers_are_jumpers no)
		(fp_poly
			(pts
				(xy -0.2794 -0.1016) (xy 0.2794 -0.1016) (xy 0.2794 0.9906) (xy -0.2794 0.9906)
			)
			(stroke
				(width 0)
				(type default)
			)
			(fill no)
			(layer "F.CrtYd")
		)
		(fp_line
			(start -0.2794 -0.1016)
			(end -0.2794 0.9906)
			(stroke
				(width 0.1)
				(type default)
			)
			(layer "F.Fab")
		)
		(fp_line
			(start -0.2794 0.9906)
			(end 0.2794 0.9906)
			(stroke
				(width 0.1)
				(type default)
			)
			(layer "F.Fab")
		)
		(fp_line
			(start 0.2794 -0.1016)
			(end -0.2794 -0.1016)
			(stroke
				(width 0.1)
				(type default)
			)
			(layer "F.Fab")
		)
		(fp_line
			(start 0.2794 0.9906)
			(end 0.2794 -0.1016)
			(stroke
				(width 0.1)
				(type default)
			)
			(layer "F.Fab")
		)
		(pad "1" smd rect
			(at 0 0)
			(size 0.508 0.508)
			(layers "F.Cu" "F.Mask" "F.Paste")
			(net "P3V3_STBY")
		)
		(pad "2" smd rect
			(at 0 0.889)
			(size 0.508 0.508)
			(layers "F.Cu" "F.Mask" "F.Paste")
			(net "FM_HEARTBEAT_LED")
		)
		(zone
			(layer "F.Cu")
			(hatch none 0.5)
			(connect_pads
				(clearance 0)
			)
			(min_thickness 0.25)
			(keepout
				(tracks allowed)
				(vias not_allowed)
				(pads allowed)
				(copperpour not_allowed)
				(footprints allowed)
			)
			(placement
				(enabled no)
				(sheetname "")
			)
			(fill
				(thermal_gap 0.5)
				(thermal_bridge_width 0.5)
				(island_removal_mode 0)
			)
			(polygon
				(pts
					(xy 455.168 -38.481) (xy 455.676 -38.481) (xy 455.676 -38.1) (xy 455.168 -38.1)
				)
			)
		)
		(zone
			(layer "F.Cu")
			(hatch none 0.5)
			(connect_pads
				(clearance 0)
			)
			(min_thickness 0.25)
			(keepout
				(tracks not_allowed)
				(vias allowed)
				(pads allowed)
				(copperpour not_allowed)
				(footprints allowed)
			)
			(placement
				(enabled no)
				(sheetname "")
			)
			(fill
				(thermal_gap 0.5)
				(thermal_bridge_width 0.5)
				(island_removal_mode 0)
			)
			(polygon
				(pts
					(xy 455.168 -38.1) (xy 455.676 -38.1) (xy 455.676 -38.481) (xy 455.168 -38.481)
				)
			)
		)
	)
	(footprint ""
		(layer "F.Cu")
		(at 404.43658 -141.783816 -90)
		(property "Reference" "C8A14"
			(at 0 0 270)
			(layer "F.SilkS")
			(hide yes)
			(effects
				(font
					(size 1.27 1.27)
				)
			)
		)
		(property "Value" ""
			(at 0 0 270)
			(layer "F.Fab")
			(effects
				(font
					(size 1.27 1.27)
				)
			)
		)
		(duplicate_pad_numbers_are_jumpers no)
		(fp_poly
			(pts
				(xy -0.7239 -0.2159) (xy 0.7239 -0.2159) (xy 0.7239 1.9939) (xy -0.7239 1.9939)
			)
			(stroke
				(width 0)
				(type default)
			)
			(fill no)
			(layer "F.CrtYd")
		)
		(fp_line
			(start -0.7239 1.9939)
			(end 0.7239 1.9939)
			(stroke
				(width 0.1)
				(type default)
			)
			(layer "F.Fab")
		)
		(fp_line
			(start 0.7239 1.9939)
			(end 0.7239 -0.2159)
			(stroke
				(width 0.1)
				(type default)
			)
			(layer "F.Fab")
		)
		(fp_line
			(start -0.7239 -0.2159)
			(end -0.7239 1.9939)
			(stroke
				(width 0.1)
				(type default)
			)
			(layer "F.Fab")
		)
		(fp_line
			(start 0.7239 -0.2159)
			(end -0.7239 -0.2159)
			(stroke
				(width 0.1)
				(type default)
			)
			(layer "F.Fab")
		)
		(pad "1" smd rect
			(at 0 0 270)
			(size 1.27 1.016)
			(layers "F.Cu" "F.Mask" "F.Paste")
			(net "P1V8_PCH_STBY")
		)
		(pad "2" smd rect
			(at 0 1.778 270)
			(size 1.27 1.016)
			(layers "F.Cu" "F.Mask" "F.Paste")
			(net "GND")
		)
		(zone
			(layer "F.Cu")
			(hatch none 0.5)
			(connect_pads
				(clearance 0)
			)
			(min_thickness 0.25)
			(keepout
				(tracks not_allowed)
				(vias allowed)
				(pads allowed)
				(copperpour not_allowed)
				(footprints allowed)
			)
			(placement
				(enabled no)
				(sheetname "")
			)
			(fill
				(thermal_gap 0.5)
				(thermal_bridge_width 0.5)
				(island_removal_mode 0)
			)
			(polygon
				(pts
					(xy 403.92858 -142.418816) (xy 403.92858 -141.148816) (xy 403.16658 -141.148816) (xy 403.16658 -142.418816)
				)
			)
		)
	)
	(footprint ""
		(layer "F.Cu")
		(at 369.333526 -104.309164 90)
		(property "Reference" "R7C4"
			(at 0 0 90)
			(layer "F.SilkS")
			(hide yes)
			(effects
				(font
					(size 1.27 1.27)
				)
			)
		)
		(property "Value" ""
			(at 0 0 90)
			(layer "F.Fab")
			(effects
				(font
					(size 1.27 1.27)
				)
			)
		)
		(duplicate_pad_numbers_are_jumpers no)
		(fp_poly
			(pts
				(xy -0.2794 -0.1016) (xy 0.2794 -0.1016) (xy 0.2794 0.9906) (xy -0.2794 0.9906)
			)
			(stroke
				(width 0)
				(type default)
			)
			(fill no)
			(layer "F.CrtYd")
		)
		(fp_line
			(start 0.2794 -0.1016)
			(end -0.2794 -0.1016)
			(stroke
				(width 0.1)
				(type default)
			)
			(layer "F.Fab")
		)
		(fp_line
			(start -0.2794 -0.1016)
			(end -0.2794 0.9906)
			(stroke
				(width 0.1)
				(type default)
			)
			(layer "F.Fab")
		)
		(fp_line
			(start 0.2794 0.9906)
			(end 0.2794 -0.1016)
			(stroke
				(width 0.1)
				(type default)
			)
			(layer "F.Fab")
		)
		(fp_line
			(start -0.2794 0.9906)
			(end 0.2794 0.9906)
			(stroke
				(width 0.1)
				(type default)
			)
			(layer "F.Fab")
		)
		(pad "1" smd rect
			(at 0 0 90)
			(size 0.508 0.508)
			(layers "F.Cu" "F.Mask" "F.Paste")
			(net "CLK_100M_BMC_PE_R_DP")
		)
		(pad "2" smd rect
			(at 0 0.889 90)
			(size 0.508 0.508)
			(layers "F.Cu" "F.Mask" "F.Paste")
			(net "CLK_100M_BMC_PE_DP")
		)
		(zone
			(layer "F.Cu")
			(hatch none 0.5)
			(connect_pads
				(clearance 0)
			)
			(min_thickness 0.25)
			(keepout
				(tracks allowed)
				(vias not_allowed)
				(pads allowed)
				(copperpour not_allowed)
				(footprints allowed)
			)
			(placement
				(enabled no)
				(sheetname "")
			)
			(fill
				(thermal_gap 0.5)
				(thermal_bridge_width 0.5)
				(island_removal_mode 0)
			)
			(polygon
				(pts
					(xy 369.587526 -104.055164) (xy 369.587526 -104.563164) (xy 369.968526 -104.563164) (xy 369.968526 -104.055164)
				)
			)
		)
		(zone
			(layer "F.Cu")
			(hatch none 0.5)
			(connect_pads
				(clearance 0)
			)
			(min_thickness 0.25)
			(keepout
				(tracks not_allowed)
				(vias allowed)
				(pads allowed)
				(copperpour not_allowed)
				(footprints allowed)
			)
			(placement
				(enabled no)
				(sheetname "")
			)
			(fill
				(thermal_gap 0.5)
				(thermal_bridge_width 0.5)
				(island_removal_mode 0)
			)
			(polygon
				(pts
					(xy 369.968526 -104.055164) (xy 369.968526 -104.563164) (xy 369.587526 -104.563164) (xy 369.587526 -104.055164)
				)
			)
		)
	)
)
